(kicad_pcb
	(version 20260206)
	(generator "pcbnew")
	(generator_version "10.0")
	(general
		(thickness 1.6)
		(legacy_teardrops no)
	)
	(paper "A4")
	(title_block
		(title "01162023_DA0F0TEBIF0_F0T_Expander_BD_F_brd_V02_OCP.brd")
		(comment 1 "Grand Teton / footprints 364-370 of 9728")
	)
	(layers
		(0 "F.Cu" signal "TOP")
		(4 "In1.Cu" signal "GND")
		(6 "In2.Cu" signal "VCC")
		(8 "In3.Cu" signal "VCC1")
		(10 "In4.Cu" signal "GND1")
		(12 "In5.Cu" signal "IN1")
		(14 "In6.Cu" signal "GND2")
		(16 "In7.Cu" signal "IN2")
		(18 "In8.Cu" signal "GND3")
		(20 "In9.Cu" signal "IN3")
		(22 "In10.Cu" signal "GND4")
		(24 "In11.Cu" signal "IN4")
		(26 "In12.Cu" signal "GND5")
		(28 "In13.Cu" signal "IN5")
		(30 "In14.Cu" signal "GND6")
		(32 "In15.Cu" signal "IN6")
		(34 "In16.Cu" signal "GND7")
		(2 "B.Cu" signal "BOTTOM")
		(9 "F.Adhes" user "F.Adhesive")
		(11 "B.Adhes" user "B.Adhesive")
		(13 "F.Paste" user "Package Geometry/Pastemask Top")
		(15 "B.Paste" user "Package Geometry/Pastemask Bottom")
		(5 "F.SilkS" user "Ref Des/Silkscreen Top")
		(7 "B.SilkS" user "Ref Des/Silkscreen Bottom")
		(1 "F.Mask" user "Board Geometry/Soldermask Top")
		(3 "B.Mask" user "Board Geometry/Soldermask Bottom")
		(17 "Dwgs.User" user "User.Drawings")
		(19 "Cmts.User" user "User.Comments")
		(21 "Eco1.User" user "User.Eco1")
		(23 "Eco2.User" user "User.Eco2")
		(25 "Edge.Cuts" user "Board Geometry/Outline")
		(27 "Margin" user)
		(31 "F.CrtYd" user "Package Geometry/Place Bound Top")
		(29 "B.CrtYd" user "Package Geometry/Place Bound Bottom")
		(35 "F.Fab" user "Ref Des/Assembly Top")
		(33 "B.Fab" user "Ref Des/Assembly Bottom")
	)
	(footprint ""
		(layer "F.Cu")
		(at 369.011454 -9.955022)
		(property "Reference" "R5809"
			(at 0 0 0)
			(layer "F.SilkS")
			(hide yes)
			(effects
				(font
					(size 1.27 1.27)
				)
			)
		)
		(property "Value" ""
			(at 0 0 0)
			(layer "F.Fab")
			(effects
				(font
					(size 1.27 1.27)
				)
			)
		)
		(duplicate_pad_numbers_are_jumpers no)
		(fp_line
			(start -0.7874 -0.4064)
			(end 0.7874 -0.4064)
			(stroke
				(width 0.1524)
				(type default)
			)
			(layer "F.SilkS")
		)
		(fp_line
			(start -0.7874 0.4064)
			(end -0.7874 -0.4064)
			(stroke
				(width 0.1524)
				(type default)
			)
			(layer "F.SilkS")
		)
		(fp_line
			(start 0.7874 -0.4064)
			(end 0.7874 0.4064)
			(stroke
				(width 0.1524)
				(type default)
			)
			(layer "F.SilkS")
		)
		(fp_line
			(start 0.7874 0.4064)
			(end -0.7874 0.4064)
			(stroke
				(width 0.1524)
				(type default)
			)
			(layer "F.SilkS")
		)
		(fp_line
			(start -0.67945 -0.305054)
			(end -0.12065 -0.305054)
			(stroke
				(width 0.1)
				(type default)
			)
			(layer "F.Fab")
		)
		(fp_line
			(start -0.67945 0.3048)
			(end -0.67945 -0.305054)
			(stroke
				(width 0.1)
				(type default)
			)
			(layer "F.Fab")
		)
		(fp_line
			(start -0.12065 -0.305054)
			(end -0.12065 -0.2794)
			(stroke
				(width 0.1)
				(type default)
			)
			(layer "F.Fab")
		)
		(fp_line
			(start -0.12065 -0.2794)
			(end 0.12065 -0.2794)
			(stroke
				(width 0.1)
				(type default)
			)
			(layer "F.Fab")
		)
		(fp_line
			(start -0.12065 0.2794)
			(end -0.12065 0.3048)
			(stroke
				(width 0.1)
				(type default)
			)
			(layer "F.Fab")
		)
		(fp_line
			(start -0.12065 0.3048)
			(end -0.67945 0.3048)
			(stroke
				(width 0.1)
				(type default)
			)
			(layer "F.Fab")
		)
		(fp_line
			(start 0.120396 0.2794)
			(end -0.12065 0.2794)
			(stroke
				(width 0.1)
				(type default)
			)
			(layer "F.Fab")
		)
		(fp_line
			(start 0.120396 0.3048)
			(end 0.120396 0.2794)
			(stroke
				(width 0.1)
				(type default)
			)
			(layer "F.Fab")
		)
		(fp_line
			(start 0.12065 -0.3048)
			(end 0.67945 -0.3048)
			(stroke
				(width 0.1)
				(type default)
			)
			(layer "F.Fab")
		)
		(fp_line
			(start 0.12065 -0.2794)
			(end 0.12065 -0.3048)
			(stroke
				(width 0.1)
				(type default)
			)
			(layer "F.Fab")
		)
		(fp_line
			(start 0.67945 -0.3048)
			(end 0.67945 0.3048)
			(stroke
				(width 0.1)
				(type default)
			)
			(layer "F.Fab")
		)
		(fp_line
			(start 0.67945 0.3048)
			(end 0.120396 0.3048)
			(stroke
				(width 0.1)
				(type default)
			)
			(layer "F.Fab")
		)
		(pad "1" smd circle
			(at -0.40005 0)
			(size 0 0)
			(layers "F.Cu" "F.Mask" "F.Paste")
			(net "SMB_BIC_I2C6_MUX_THERMAL_R2_SCL")
		)
		(pad "2" smd circle
			(at 0.40005 0)
			(size 0 0)
			(layers "F.Cu" "F.Mask" "F.Paste")
			(net "SMB_LM75_2_SCL")
		)
	)
	(footprint ""
		(layer "F.Cu")
		(at 249.992388 -32.739584 180)
		(property "Reference" "C489"
			(at 0 0 180)
			(layer "F.SilkS")
			(hide yes)
			(effects
				(font
					(size 1.27 1.27)
				)
			)
		)
		(property "Value" ""
			(at 0 0 180)
			(layer "F.Fab")
			(effects
				(font
					(size 1.27 1.27)
				)
			)
		)
		(duplicate_pad_numbers_are_jumpers no)
		(fp_line
			(start 0.299974 0.150114)
			(end -0.299974 0.150114)
			(stroke
				(width 0.1)
				(type default)
			)
			(layer "F.Fab")
		)
		(fp_line
			(start 0.299974 -0.150114)
			(end 0.299974 0.150114)
			(stroke
				(width 0.1)
				(type default)
			)
			(layer "F.Fab")
		)
		(fp_line
			(start -0.299974 0.150114)
			(end -0.299974 -0.150114)
			(stroke
				(width 0.1)
				(type default)
			)
			(layer "F.Fab")
		)
		(fp_line
			(start -0.299974 -0.150114)
			(end 0.299974 -0.150114)
			(stroke
				(width 0.1)
				(type default)
			)
			(layer "F.Fab")
		)
		(pad "1" smd rect
			(at -0.2667 0 180)
			(size 0.3048 0.381)
			(layers "F.Cu" "F.Mask" "F.Paste")
			(net "P5E_PEX2_STN2_TX_DP<46>")
		)
		(pad "2" smd rect
			(at 0.2667 0 180)
			(size 0.3048 0.381)
			(layers "F.Cu" "F.Mask" "F.Paste")
			(net "P5E_PEX2_STN2_TX_C_DP<46>")
		)
	)
	(footprint ""
		(layer "F.Cu")
		(at 143.490442 -250.070874 -90)
		(property "Reference" "R1274"
			(at 0 0 270)
			(layer "F.SilkS")
			(hide yes)
			(effects
				(font
					(size 1.27 1.27)
				)
			)
		)
		(property "Value" ""
			(at 0 0 270)
			(layer "F.Fab")
			(effects
				(font
					(size 1.27 1.27)
				)
			)
		)
		(duplicate_pad_numbers_are_jumpers no)
		(fp_line
			(start -0.7874 0.4064)
			(end -0.7874 -0.4064)
			(stroke
				(width 0.1524)
				(type default)
			)
			(layer "F.SilkS")
		)
		(fp_line
			(start 0.7874 0.4064)
			(end -0.7874 0.4064)
			(stroke
				(width 0.1524)
				(type default)
			)
			(layer "F.SilkS")
		)
		(fp_line
			(start -0.7874 -0.4064)
			(end 0.7874 -0.4064)
			(stroke
				(width 0.1524)
				(type default)
			)
			(layer "F.SilkS")
		)
		(fp_line
			(start 0.7874 -0.4064)
			(end 0.7874 0.4064)
			(stroke
				(width 0.1524)
				(type default)
			)
			(layer "F.SilkS")
		)
		(fp_line
			(start -0.67945 0.3048)
			(end -0.67945 -0.305054)
			(stroke
				(width 0.1)
				(type default)
			)
			(layer "F.Fab")
		)
		(fp_line
			(start -0.12065 0.3048)
			(end -0.67945 0.3048)
			(stroke
				(width 0.1)
				(type default)
			)
			(layer "F.Fab")
		)
		(fp_line
			(start 0.120396 0.3048)
			(end 0.120396 0.2794)
			(stroke
				(width 0.1)
				(type default)
			)
			(layer "F.Fab")
		)
		(fp_line
			(start 0.67945 0.3048)
			(end 0.120396 0.3048)
			(stroke
				(width 0.1)
				(type default)
			)
			(layer "F.Fab")
		)
		(fp_line
			(start -0.12065 0.2794)
			(end -0.12065 0.3048)
			(stroke
				(width 0.1)
				(type default)
			)
			(layer "F.Fab")
		)
		(fp_line
			(start 0.120396 0.2794)
			(end -0.12065 0.2794)
			(stroke
				(width 0.1)
				(type default)
			)
			(layer "F.Fab")
		)
		(fp_line
			(start -0.12065 -0.2794)
			(end 0.12065 -0.2794)
			(stroke
				(width 0.1)
				(type default)
			)
			(layer "F.Fab")
		)
		(fp_line
			(start 0.12065 -0.2794)
			(end 0.12065 -0.3048)
			(stroke
				(width 0.1)
				(type default)
			)
			(layer "F.Fab")
		)
		(fp_line
			(start 0.12065 -0.3048)
			(end 0.67945 -0.3048)
			(stroke
				(width 0.1)
				(type default)
			)
			(layer "F.Fab")
		)
		(fp_line
			(start 0.67945 -0.3048)
			(end 0.67945 0.3048)
			(stroke
				(width 0.1)
				(type default)
			)
			(layer "F.Fab")
		)
		(fp_line
			(start -0.67945 -0.305054)
			(end -0.12065 -0.305054)
			(stroke
				(width 0.1)
				(type default)
			)
			(layer "F.Fab")
		)
		(fp_line
			(start -0.12065 -0.305054)
			(end -0.12065 -0.2794)
			(stroke
				(width 0.1)
				(type default)
			)
			(layer "F.Fab")
		)
		(pad "1" smd circle
			(at -0.40005 0 270)
			(size 0 0)
			(layers "F.Cu" "F.Mask" "F.Paste")
			(net "PEX1_MODE_SEL5")
		)
		(pad "2" smd circle
			(at 0.40005 0 270)
			(size 0 0)
			(layers "F.Cu" "F.Mask" "F.Paste")
			(net "P1V8_PEX")
		)
	)
	(footprint ""
		(layer "F.Cu")
		(at 108.496354 -79.822294 90)
		(property "Reference" "R1139"
			(at 0 0 90)
			(layer "F.SilkS")
			(hide yes)
			(effects
				(font
					(size 1.27 1.27)
				)
			)
		)
		(property "Value" ""
			(at 0 0 90)
			(layer "F.Fab")
			(effects
				(font
					(size 1.27 1.27)
				)
			)
		)
		(duplicate_pad_numbers_are_jumpers no)
		(fp_line
			(start 0.7874 0.4064)
			(end -0.7874 0.4064)
			(stroke
				(width 0.1524)
				(type default)
			)
			(layer "F.SilkS")
		)
		(fp_line
			(start -0.12065 -0.305054)
			(end -0.12065 -0.2794)
			(stroke
				(width 0.1)
				(type default)
			)
			(layer "F.Fab")
		)
		(fp_line
			(start -0.67945 -0.305054)
			(end -0.12065 -0.305054)
			(stroke
				(width 0.1)
				(type default)
			)
			(layer "F.Fab")
		)
		(fp_line
			(start 0.67945 -0.3048)
			(end 0.67945 0.3048)
			(stroke
				(width 0.1)
				(type default)
			)
			(layer "F.Fab")
		)
		(fp_line
			(start 0.12065 -0.3048)
			(end 0.67945 -0.3048)
			(stroke
				(width 0.1)
				(type default)
			)
			(layer "F.Fab")
		)
		(fp_line
			(start 0.12065 -0.2794)
			(end 0.12065 -0.3048)
			(stroke
				(width 0.1)
				(type default)
			)
			(layer "F.Fab")
		)
		(fp_line
			(start -0.12065 -0.2794)
			(end 0.12065 -0.2794)
			(stroke
				(width 0.1)
				(type default)
			)
			(layer "F.Fab")
		)
		(fp_line
			(start 0.120396 0.2794)
			(end -0.12065 0.2794)
			(stroke
				(width 0.1)
				(type default)
			)
			(layer "F.Fab")
		)
		(fp_line
			(start -0.12065 0.2794)
			(end -0.12065 0.3048)
			(stroke
				(width 0.1)
				(type default)
			)
			(layer "F.Fab")
		)
		(fp_line
			(start 0.67945 0.3048)
			(end 0.120396 0.3048)
			(stroke
				(width 0.1)
				(type default)
			)
			(layer "F.Fab")
		)
		(fp_line
			(start 0.120396 0.3048)
			(end 0.120396 0.2794)
			(stroke
				(width 0.1)
				(type default)
			)
			(layer "F.Fab")
		)
		(fp_line
			(start -0.12065 0.3048)
			(end -0.67945 0.3048)
			(stroke
				(width 0.1)
				(type default)
			)
			(layer "F.Fab")
		)
		(fp_line
			(start -0.67945 0.3048)
			(end -0.67945 -0.305054)
			(stroke
				(width 0.1)
				(type default)
			)
			(layer "F.Fab")
		)
		(pad "1" smd circle
			(at -0.40005 0 90)
			(size 0 0)
			(layers "F.Cu" "F.Mask" "F.Paste")
			(net "CLK_100M_DB800ZL_SSD1_R_DN")
		)
		(pad "2" smd circle
			(at 0.40005 0 90)
			(size 0 0)
			(layers "F.Cu" "F.Mask" "F.Paste")
			(net "CLK_100M_DB800ZL_SSD1_DN")
		)
	)
	(footprint ""
		(layer "F.Cu")
		(at 235.690664 -206.51216 -90)
		(property "Reference" "R5501"
			(at 0 0 270)
			(layer "F.SilkS")
			(hide yes)
			(effects
				(font
					(size 1.27 1.27)
				)
			)
		)
		(property "Value" ""
			(at 0 0 270)
			(layer "F.Fab")
			(effects
				(font
					(size 1.27 1.27)
				)
			)
		)
		(duplicate_pad_numbers_are_jumpers no)
		(fp_line
			(start -0.7874 0.4064)
			(end -0.7874 -0.4064)
			(stroke
				(width 0.1524)
				(type default)
			)
			(layer "F.SilkS")
		)
		(fp_line
			(start 0.7874 0.4064)
			(end -0.7874 0.4064)
			(stroke
				(width 0.1524)
				(type default)
			)
			(layer "F.SilkS")
		)
		(fp_line
			(start -0.7874 -0.4064)
			(end 0.7874 -0.4064)
			(stroke
				(width 0.1524)
				(type default)
			)
			(layer "F.SilkS")
		)
		(fp_line
			(start 0.7874 -0.4064)
			(end 0.7874 0.4064)
			(stroke
				(width 0.1524)
				(type default)
			)
			(layer "F.SilkS")
		)
		(fp_line
			(start -0.67945 0.3048)
			(end -0.67945 -0.305054)
			(stroke
				(width 0.1)
				(type default)
			)
			(layer "F.Fab")
		)
		(fp_line
			(start -0.12065 0.3048)
			(end -0.67945 0.3048)
			(stroke
				(width 0.1)
				(type default)
			)
			(layer "F.Fab")
		)
		(fp_line
			(start 0.120396 0.3048)
			(end 0.120396 0.2794)
			(stroke
				(width 0.1)
				(type default)
			)
			(layer "F.Fab")
		)
		(fp_line
			(start 0.67945 0.3048)
			(end 0.120396 0.3048)
			(stroke
				(width 0.1)
				(type default)
			)
			(layer "F.Fab")
		)
		(fp_line
			(start -0.12065 0.2794)
			(end -0.12065 0.3048)
			(stroke
				(width 0.1)
				(type default)
			)
			(layer "F.Fab")
		)
		(fp_line
			(start 0.120396 0.2794)
			(end -0.12065 0.2794)
			(stroke
				(width 0.1)
				(type default)
			)
			(layer "F.Fab")
		)
		(fp_line
			(start -0.12065 -0.2794)
			(end 0.12065 -0.2794)
			(stroke
				(width 0.1)
				(type default)
			)
			(layer "F.Fab")
		)
		(fp_line
			(start 0.12065 -0.2794)
			(end 0.12065 -0.3048)
			(stroke
				(width 0.1)
				(type default)
			)
			(layer "F.Fab")
		)
		(fp_line
			(start 0.12065 -0.3048)
			(end 0.67945 -0.3048)
			(stroke
				(width 0.1)
				(type default)
			)
			(layer "F.Fab")
		)
		(fp_line
			(start 0.67945 -0.3048)
			(end 0.67945 0.3048)
			(stroke
				(width 0.1)
				(type default)
			)
			(layer "F.Fab")
		)
		(fp_line
			(start -0.67945 -0.305054)
			(end -0.12065 -0.305054)
			(stroke
				(width 0.1)
				(type default)
			)
			(layer "F.Fab")
		)
		(fp_line
			(start -0.12065 -0.305054)
			(end -0.12065 -0.2794)
			(stroke
				(width 0.1)
				(type default)
			)
			(layer "F.Fab")
		)
		(pad "1" smd circle
			(at -0.40005 0 270)
			(size 0 0)
			(layers "F.Cu" "F.Mask" "F.Paste")
			(net "RST_BIC_EXTRST_N")
		)
		(pad "2" smd circle
			(at 0.40005 0 270)
			(size 0 0)
			(layers "F.Cu" "F.Mask" "F.Paste")
			(net "RST_BIC_SRST_BIC_N")
		)
	)
	(footprint ""
		(layer "F.Cu")
		(at 95.946976 -55.63489 90)
		(property "Reference" "PC393"
			(at 0 0 90)
			(layer "F.SilkS")
			(hide yes)
			(effects
				(font
					(size 1.27 1.27)
				)
			)
		)
		(property "Value" ""
			(at 0 0 90)
			(layer "F.Fab")
			(effects
				(font
					(size 1.27 1.27)
				)
			)
		)
		(duplicate_pad_numbers_are_jumpers no)
		(fp_line
			(start 1.524 -0.762)
			(end 1.524 0.762)
			(stroke
				(width 0.1524)
				(type default)
			)
			(layer "F.SilkS")
		)
		(fp_line
			(start -1.524 -0.762)
			(end 1.524 -0.762)
			(stroke
				(width 0.1524)
				(type default)
			)
			(layer "F.SilkS")
		)
		(fp_line
			(start 1.524 0.762)
			(end -1.524 0.762)
			(stroke
				(width 0.1524)
				(type default)
			)
			(layer "F.SilkS")
		)
		(fp_line
			(start -1.524 0.762)
			(end -1.524 -0.762)
			(stroke
				(width 0.1524)
				(type default)
			)
			(layer "F.SilkS")
		)
		(fp_line
			(start 1.1049 -0.724916)
			(end -1.1049 -0.724916)
			(stroke
				(width 0.1)
				(type default)
			)
			(layer "F.Fab")
		)
		(fp_line
			(start -1.1049 -0.724916)
			(end -1.1049 0.724916)
			(stroke
				(width 0.1)
				(type default)
			)
			(layer "F.Fab")
		)
		(fp_line
			(start 1.1049 0.724916)
			(end 1.1049 -0.724916)
			(stroke
				(width 0.1)
				(type default)
			)
			(layer "F.Fab")
		)
		(fp_line
			(start -1.1049 0.724916)
			(end 1.1049 0.724916)
			(stroke
				(width 0.1)
				(type default)
			)
			(layer "F.Fab")
		)
		(pad "1" smd rect
			(at -0.889 0 270)
			(size 1.016 1.27)
			(layers "F.Cu" "F.Mask" "F.Paste")
			(net "P12V_SSD3_R")
		)
		(pad "2" smd rect
			(at 0.889 0 270)
			(size 1.016 1.27)
			(layers "F.Cu" "F.Mask" "F.Paste")
			(net "GND")
		)
	)
	(footprint ""
		(layer "F.Cu")
		(at 255.856486 -17.419574 180)
		(property "Reference" "R1688"
			(at 0 0 180)
			(layer "F.SilkS")
			(hide yes)
			(effects
				(font
					(size 1.27 1.27)
				)
			)
		)
		(property "Value" ""
			(at 0 0 180)
			(layer "F.Fab")
			(effects
				(font
					(size 1.27 1.27)
				)
			)
		)
		(duplicate_pad_numbers_are_jumpers no)
		(fp_line
			(start 0.7874 0.4064)
			(end -0.7874 0.4064)
			(stroke
				(width 0.1524)
				(type default)
			)
			(layer "F.SilkS")
		)
		(fp_line
			(start 0.7874 -0.4064)
			(end 0.7874 0.4064)
			(stroke
				(width 0.1524)
				(type default)
			)
			(layer "F.SilkS")
		)
		(fp_line
			(start -0.7874 0.4064)
			(end -0.7874 -0.4064)
			(stroke
				(width 0.1524)
				(type default)
			)
			(layer "F.SilkS")
		)
		(fp_line
			(start -0.7874 -0.4064)
			(end 0.7874 -0.4064)
			(stroke
				(width 0.1524)
				(type default)
			)
			(layer "F.SilkS")
		)
		(fp_line
			(start 0.67945 0.3048)
			(end 0.120396 0.3048)
			(stroke
				(width 0.1)
				(type default)
			)
			(layer "F.Fab")
		)
		(fp_line
			(start 0.67945 -0.3048)
			(end 0.67945 0.3048)
			(stroke
				(width 0.1)
				(type default)
			)
			(layer "F.Fab")
		)
		(fp_line
			(start 0.12065 -0.2794)
			(end 0.12065 -0.3048)
			(stroke
				(width 0.1)
				(type default)
			)
			(layer "F.Fab")
		)
		(fp_line
			(start 0.12065 -0.3048)
			(end 0.67945 -0.3048)
			(stroke
				(width 0.1)
				(type default)
			)
			(layer "F.Fab")
		)
		(fp_line
			(start 0.120396 0.3048)
			(end 0.120396 0.2794)
			(stroke
				(width 0.1)
				(type default)
			)
			(layer "F.Fab")
		)
		(fp_line
			(start 0.120396 0.2794)
			(end -0.12065 0.2794)
			(stroke
				(width 0.1)
				(type default)
			)
			(layer "F.Fab")
		)
		(fp_line
			(start -0.12065 0.3048)
			(end -0.67945 0.3048)
			(stroke
				(width 0.1)
				(type default)
			)
			(layer "F.Fab")
		)
		(fp_line
			(start -0.12065 0.2794)
			(end -0.12065 0.3048)
			(stroke
				(width 0.1)
				(type default)
			)
			(layer "F.Fab")
		)
		(fp_line
			(start -0.12065 -0.2794)
			(end 0.12065 -0.2794)
			(stroke
				(width 0.1)
				(type default)
			)
			(layer "F.Fab")
		)
		(fp_line
			(start -0.12065 -0.305054)
			(end -0.12065 -0.2794)
			(stroke
				(width 0.1)
				(type default)
			)
			(layer "F.Fab")
		)
		(fp_line
			(start -0.67945 0.3048)
			(end -0.67945 -0.305054)
			(stroke
				(width 0.1)
				(type default)
			)
			(layer "F.Fab")
		)
		(fp_line
			(start -0.67945 -0.305054)
			(end -0.12065 -0.305054)
			(stroke
				(width 0.1)
				(type default)
			)
			(layer "F.Fab")
		)
		(pad "1" smd circle
			(at -0.40005 0 180)
			(size 0 0)
			(layers "F.Cu" "F.Mask" "F.Paste")
			(net "P3V3_SSD8")
		)
		(pad "2" smd circle
			(at 0.40005 0 180)
			(size 0 0)
			(layers "F.Cu" "F.Mask" "F.Paste")
			(net "SMB_ISO_SSD8_SCL")
		)
	)
)
